# TIMECARD (Time Appliance Project (Time Card)) — schematic netlist excerpt (pin names and nets, part order shuffled) for the footprints in the layout excerpt that follows; sources: Cadence DE-HDL packaged netlist, KiCad conversion of R4006-B0001-02_R01.brd

R475  RESISTOR  100KOHM 1%  pkg SMC_0402R_H016  page 24 : \1\ = XP3R3V_FPGA ; \2\ = FPGA_PCA9546_I2C_SCL
R167  RESISTOR  10KOHM 1%  pkg SMC_0402R_H016  page 9 : \1\ = XP3R3V_FPGA ; \2\ = FPGA_IN_RST_DLY_N

(kicad_pcb
	(version 20260206)
	(generator "pcbnew")
	(generator_version "10.0")
	(general
		(thickness 1.6)
		(legacy_teardrops no)
	)
	(paper "A4")
	(title_block
		(title "timecard-production-celestica-r4006 — R4006-B0001-02_R01.brd")
		(comment 1 "Time Appliance Project (Time Card) / footprints 65-66 of 1113")
	)
	(layers
		(0 "F.Cu" signal "TOP")
		(4 "In1.Cu" signal "L02_GND1")
		(6 "In2.Cu" signal "L03_SIG1")
		(8 "In3.Cu" signal "L04_GND2")
		(10 "In4.Cu" signal "L05_VCC1")
		(12 "In5.Cu" signal "L06_VCC2")
		(14 "In6.Cu" signal "L07_GND3")
		(16 "In7.Cu" signal "L08_SIG2")
		(18 "In8.Cu" signal "L09_GND4")
		(2 "B.Cu" signal "BOTTOM")
		(9 "F.Adhes" user "F.Adhesive")
		(11 "B.Adhes" user "B.Adhesive")
		(13 "F.Paste" user "Package Geometry/Pastemask Top")
		(15 "B.Paste" user "Package Geometry/Pastemask Bottom")
		(5 "F.SilkS" user "Ref Des/Silkscreen Top")
		(7 "B.SilkS" user "Ref Des/Silkscreen Bottom")
		(1 "F.Mask" user "Board Geometry/Soldermask Top")
		(3 "B.Mask" user "Board Geometry/Soldermask Bottom")
		(17 "Dwgs.User" user "User.Drawings")
		(19 "Cmts.User" user "User.Comments")
		(21 "Eco1.User" user "User.Eco1")
		(23 "Eco2.User" user "User.Eco2")
		(25 "Edge.Cuts" user "Board Geometry/Outline")
		(27 "Margin" user)
		(31 "F.CrtYd" user "Package Geometry/Place Bound Top")
		(29 "B.CrtYd" user "Package Geometry/Place Bound Bottom")
		(35 "F.Fab" user "Ref Des/Assembly Top")
		(33 "B.Fab" user "Ref Des/Assembly Bottom")
	)
	(footprint ""
		(layer "F.Cu")
		(at 119.761 -19.939)
		(property "Reference" "R475"
			(at -0.127 1.18237 0)
			(unlocked yes)
			(layer "F.SilkS")
			(effects
				(font
					(size 0.7874 0.5842)
					(thickness 0.1524)
				)
			)
		)
		(property "Value" "VAL*"
			(at 0.02032 2.13233 0)
			(unlocked yes)
			(layer "F.Fab")
			(hide yes)
			(effects
				(font
					(size 0.7874 0.5842)
					(thickness 0.1524)
				)
			)
		)
		(property "Tolerance" "TOL*"
			(at 0.044704 3.05435 0)
			(unlocked yes)
			(layer "Cmts.User")
			(hide yes)
			(effects
				(font
					(size 0.7874 0.5842)
					(thickness 0.1524)
				)
			)
		)
		(property "User Part Number" "PARTNUM*"
			(at 0.02032 4.024884 0)
			(unlocked yes)
			(layer "Cmts.User")
			(hide yes)
			(effects
				(font
					(size 0.7874 0.5842)
					(thickness 0.1524)
				)
			)
		)
		(property "Device Type" "RESISTOR-G155-11003-01,100KOHMA"
			(at 0.008382 1.210564 0)
			(unlocked yes)
			(layer "F.Fab")
			(hide yes)
			(effects
				(font
					(size 0.7874 0.5842)
					(thickness 0.1524)
				)
			)
		)
		(duplicate_pad_numbers_are_jumpers no)
		(fp_line
			(start -1.143 -0.5588)
			(end -1.143 0.5588)
			(stroke
				(width 0.1)
				(type default)
			)
			(layer "F.SilkS")
		)
		(fp_line
			(start -1.143 0.5588)
			(end 1.143 0.5588)
			(stroke
				(width 0.1)
				(type default)
			)
			(layer "F.SilkS")
		)
		(fp_line
			(start 1.143 -0.5588)
			(end -1.143 -0.5588)
			(stroke
				(width 0.1)
				(type default)
			)
			(layer "F.SilkS")
		)
		(fp_line
			(start 1.143 0.5588)
			(end 1.143 -0.5588)
			(stroke
				(width 0.1)
				(type default)
			)
			(layer "F.SilkS")
		)
		(fp_poly
			(pts
				(xy -1.143 0.5588) (xy 1.143 0.5588) (xy 1.143 -0.5588) (xy -1.143 -0.5588)
			)
			(stroke
				(width 0)
				(type default)
			)
			(fill no)
			(layer "F.CrtYd")
		)
		(fp_line
			(start -0.508 -0.3048)
			(end -0.508 0.3048)
			(stroke
				(width 0.1)
				(type default)
			)
			(layer "F.Fab")
		)
		(fp_line
			(start -0.508 0.3048)
			(end 0.508 0.3048)
			(stroke
				(width 0.1)
				(type default)
			)
			(layer "F.Fab")
		)
		(fp_line
			(start 0.508 -0.3048)
			(end -0.508 -0.3048)
			(stroke
				(width 0.1)
				(type default)
			)
			(layer "F.Fab")
		)
		(fp_line
			(start 0.508 0.3048)
			(end 0.508 -0.3048)
			(stroke
				(width 0.1)
				(type default)
			)
			(layer "F.Fab")
		)
		(pad "1" smd rect
			(at -0.5334 0)
			(size 0.7112 0.6096)
			(layers "F.Cu" "F.Mask" "F.Paste")
			(net "XP3R3V_FPGA")
		)
		(pad "2" smd rect
			(at 0.5334 0)
			(size 0.7112 0.6096)
			(layers "F.Cu" "F.Mask" "F.Paste")
			(net "FPGA_PCA9546_I2C_SCL")
		)
		(zone
			(layer "F.Cu")
			(hatch none 0.5)
			(connect_pads
				(clearance 0)
			)
			(min_thickness 0.25)
			(keepout
				(tracks not_allowed)
				(vias allowed)
				(pads allowed)
				(copperpour not_allowed)
				(footprints allowed)
			)
			(placement
				(enabled no)
				(sheetname "")
			)
			(fill
				(thermal_gap 0.5)
				(thermal_bridge_width 0.5)
				(island_removal_mode 0)
			)
			(polygon
				(pts
					(xy 119.6848 -19.6342) (xy 119.8372 -19.6342) (xy 119.8372 -20.2438) (xy 119.6848 -20.2438)
				)
			)
		)
		(zone
			(layer "F.Cu")
			(hatch none 0.5)
			(connect_pads
				(clearance 0)
			)
			(min_thickness 0.25)
			(keepout
				(tracks allowed)
				(vias not_allowed)
				(pads allowed)
				(copperpour not_allowed)
				(footprints allowed)
			)
			(placement
				(enabled no)
				(sheetname "")
			)
			(fill
				(thermal_gap 0.5)
				(thermal_bridge_width 0.5)
				(island_removal_mode 0)
			)
			(polygon
				(pts
					(xy 119.6848 -19.6342) (xy 119.8372 -19.6342) (xy 119.8372 -20.2438) (xy 119.6848 -20.2438)
				)
			)
		)
	)
	(footprint ""
		(layer "F.Cu")
		(at 94.234 -68.834)
		(property "Reference" "R167"
			(at -28.067 -19.39163 0)
			(unlocked yes)
			(layer "F.SilkS")
			(effects
				(font
					(size 0.7874 0.5842)
					(thickness 0.1524)
				)
			)
		)
		(property "Value" "VAL*"
			(at 0.02032 2.13233 0)
			(unlocked yes)
			(layer "F.Fab")
			(hide yes)
			(effects
				(font
					(size 0.7874 0.5842)
					(thickness 0.1524)
				)
			)
		)
		(property "Tolerance" "TOL*"
			(at 0.044704 3.05435 0)
			(unlocked yes)
			(layer "Cmts.User")
			(hide yes)
			(effects
				(font
					(size 0.7874 0.5842)
					(thickness 0.1524)
				)
			)
		)
		(property "User Part Number" "PARTNUM*"
			(at 0.02032 4.024884 0)
			(unlocked yes)
			(layer "Cmts.User")
			(hide yes)
			(effects
				(font
					(size 0.7874 0.5842)
					(thickness 0.1524)
				)
			)
		)
		(property "Device Type" "RESISTOR-G155-14701-01,4.7KOHMA"
			(at 0.008382 1.210564 0)
			(unlocked yes)
			(layer "F.Fab")
			(hide yes)
			(effects
				(font
					(size 0.7874 0.5842)
					(thickness 0.1524)
				)
			)
		)
		(duplicate_pad_numbers_are_jumpers no)
		(fp_line
			(start -1.143 -0.5588)
			(end -1.143 0.5588)
			(stroke
				(width 0.1)
				(type default)
			)
			(layer "F.SilkS")
		)
		(fp_line
			(start -1.143 0.5588)
			(end 1.143 0.5588)
			(stroke
				(width 0.1)
				(type default)
			)
			(layer "F.SilkS")
		)
		(fp_line
			(start 1.143 -0.5588)
			(end -1.143 -0.5588)
			(stroke
				(width 0.1)
				(type default)
			)
			(layer "F.SilkS")
		)
		(fp_line
			(start 1.143 0.5588)
			(end 1.143 -0.5588)
			(stroke
				(width 0.1)
				(type default)
			)
			(layer "F.SilkS")
		)
		(fp_poly
			(pts
				(xy -1.143 0.5588) (xy 1.143 0.5588) (xy 1.143 -0.5588) (xy -1.143 -0.5588)
			)
			(stroke
				(width 0)
				(type default)
			)
			(fill no)
			(layer "F.CrtYd")
		)
		(fp_line
			(start -0.508 -0.3048)
			(end -0.508 0.3048)
			(stroke
				(width 0.1)
				(type default)
			)
			(layer "F.Fab")
		)
		(fp_line
			(start -0.508 0.3048)
			(end 0.508 0.3048)
			(stroke
				(width 0.1)
				(type default)
			)
			(layer "F.Fab")
		)
		(fp_line
			(start 0.508 -0.3048)
			(end -0.508 -0.3048)
			(stroke
				(width 0.1)
				(type default)
			)
			(layer "F.Fab")
		)
		(fp_line
			(start 0.508 0.3048)
			(end 0.508 -0.3048)
			(stroke
				(width 0.1)
				(type default)
			)
			(layer "F.Fab")
		)
		(pad "1" smd rect
			(at -0.5334 0)
			(size 0.7112 0.6096)
			(layers "F.Cu" "F.Mask" "F.Paste")
			(net "XP3R3V_FPGA")
		)
		(pad "2" smd rect
			(at 0.5334 0)
			(size 0.7112 0.6096)
			(layers "F.Cu" "F.Mask" "F.Paste")
			(net "FPGA_IN_RST_DLY_N")
		)
		(zone
			(layer "F.Cu")
			(hatch none 0.5)
			(connect_pads
				(clearance 0)
			)
			(min_thickness 0.25)
			(keepout
				(tracks allowed)
				(vias not_allowed)
				(pads allowed)
				(copperpour not_allowed)
				(footprints allowed)
			)
			(placement
				(enabled no)
				(sheetname "")
			)
			(fill
				(thermal_gap 0.5)
				(thermal_bridge_width 0.5)
				(island_removal_mode 0)
			)
			(polygon
				(pts
					(xy 94.1578 -68.5292) (xy 94.3102 -68.5292) (xy 94.3102 -69.1388) (xy 94.1578 -69.1388)
				)
			)
		)
		(zone
			(layer "F.Cu")
			(hatch none 0.5)
			(connect_pads
				(clearance 0)
			)
			(min_thickness 0.25)
			(keepout
				(tracks not_allowed)
				(vias allowed)
				(pads allowed)
				(copperpour not_allowed)
				(footprints allowed)
			)
			(placement
				(enabled no)
				(sheetname "")
			)
			(fill
				(thermal_gap 0.5)
				(thermal_bridge_width 0.5)
				(island_removal_mode 0)
			)
			(polygon
				(pts
					(xy 94.1578 -68.5292) (xy 94.3102 -68.5292) (xy 94.3102 -69.1388) (xy 94.1578 -69.1388)
				)
			)
		)
	)
)
